(kicad_pcb
	(version 20260206)
	(generator "pcbnew")
	(generator_version "10.0")
	(general
		(thickness 1.6)
		(legacy_teardrops no)
	)
	(paper "A4")
	(title_block
		(title "Bryce Canyon_F.DPB_16315-1-OCP.brd")
		(comment 1 "Bryce Canyon / footprints 289-294 of 2223")
	)
	(layers
		(0 "F.Cu" signal "TOP")
		(4 "In1.Cu" signal "L2GND")
		(6 "In2.Cu" signal "L3")
		(8 "In3.Cu" signal "L4GND")
		(10 "In4.Cu" signal "L5")
		(12 "In5.Cu" signal "L6VCC")
		(14 "In6.Cu" signal "L7VCC")
		(16 "In7.Cu" signal "L8")
		(18 "In8.Cu" signal "L9GND")
		(20 "In9.Cu" signal "L10")
		(22 "In10.Cu" signal "L11GND")
		(2 "B.Cu" signal "BOTTOM")
		(9 "F.Adhes" user "F.Adhesive")
		(11 "B.Adhes" user "B.Adhesive")
		(13 "F.Paste" user "Package Geometry/Pastemask Top")
		(15 "B.Paste" user "Package Geometry/Pastemask Bottom")
		(5 "F.SilkS" user "Ref Des/Silkscreen Top")
		(7 "B.SilkS" user "Ref Des/Silkscreen Bottom")
		(1 "F.Mask" user "Board Geometry/Soldermask Top")
		(3 "B.Mask" user "Board Geometry/Soldermask Bottom")
		(17 "Dwgs.User" user "User.Drawings")
		(19 "Cmts.User" user "User.Comments")
		(21 "Eco1.User" user "User.Eco1")
		(23 "Eco2.User" user "User.Eco2")
		(25 "Edge.Cuts" user "Board Geometry/Outline")
		(27 "Margin" user)
		(31 "F.CrtYd" user "Package Geometry/Place Bound Top")
		(29 "B.CrtYd" user "Package Geometry/Place Bound Bottom")
		(35 "F.Fab" user "Ref Des/Assembly Top")
		(33 "B.Fab" user "Ref Des/Assembly Bottom")
	)
	(footprint ""
		(layer "F.Cu")
		(at 257.994912 -230.251)
		(property "Reference" "R434"
			(at 0 0 0)
			(layer "F.SilkS")
			(hide yes)
			(effects
				(font
					(size 1.27 1.27)
				)
			)
		)
		(property "Value" "1KR2F-3-GP"
			(at 0.064008 -3.993896 0)
			(unlocked yes)
			(layer "F.Fab")
			(hide yes)
			(effects
				(font
					(size 1.016 1.016)
					(thickness 0.1524)
				)
			)
		)
		(property "Device Type" "R402H16"
			(at 0.064008 -5.517896 0)
			(unlocked yes)
			(layer "F.Fab")
			(hide yes)
			(effects
				(font
					(size 1.016 1.016)
					(thickness 0.1524)
				)
			)
		)
		(duplicate_pad_numbers_are_jumpers no)
		(fp_line
			(start -0.508 -0.9398)
			(end -0.508 0.9398)
			(stroke
				(width 0.1524)
				(type default)
			)
			(layer "F.SilkS")
		)
		(fp_line
			(start 0.508 -0.9398)
			(end -0.508 -0.9398)
			(stroke
				(width 0.1524)
				(type default)
			)
			(layer "F.SilkS")
		)
		(fp_rect
			(start -0.508 0.9398)
			(end 0.508 -0.9398)
			(stroke
				(width 0)
				(type default)
			)
			(fill no)
			(layer "F.CrtYd")
		)
		(fp_rect
			(start -0.508 0.9398)
			(end 0.508 -0.9398)
			(stroke
				(width 0)
				(type default)
			)
			(fill no)
			(layer "F.Fab")
		)
		(pad "1" smd custom
			(at 0 -0.4445)
			(size 0.1397 0.1397)
			(layers "F.Cu" "F.Mask" "F.Paste")
			(net "P3V3_STBY_A")
			(options
				(clearance outline)
				(anchor circle)
			)
			(primitives
				(gr_poly
					(pts
						(arc
							(start -0.1778 -0.2794)
							(mid -0.249642 -0.249642)
							(end -0.2794 -0.1778)
						)
						(arc
							(start -0.2794 0.1778)
							(mid -0.249642 0.249642)
							(end -0.1778 0.2794)
						)
						(arc
							(start 0.1778 0.2794)
							(mid 0.249642 0.249642)
							(end 0.2794 0.1778)
						)
						(arc
							(start 0.2794 -0.1778)
							(mid 0.249642 -0.249642)
							(end 0.1778 -0.2794)
						)
					)
					(width 0)
					(fill yes)
				)
			)
		)
		(pad "2" smd custom
			(at 0 0.4445)
			(size 0.1397 0.1397)
			(layers "F.Cu" "F.Mask" "F.Paste")
			(net "I2C_DRIVE_A_PWR_SCL")
			(options
				(clearance outline)
				(anchor circle)
			)
			(primitives
				(gr_poly
					(pts
						(arc
							(start -0.1778 -0.2794)
							(mid -0.249642 -0.249642)
							(end -0.2794 -0.1778)
						)
						(arc
							(start -0.2794 0.1778)
							(mid -0.249642 0.249642)
							(end -0.1778 0.2794)
						)
						(arc
							(start 0.1778 0.2794)
							(mid 0.249642 0.249642)
							(end 0.2794 0.1778)
						)
						(arc
							(start 0.2794 -0.1778)
							(mid 0.249642 -0.249642)
							(end 0.1778 -0.2794)
						)
					)
					(width 0)
					(fill yes)
				)
			)
		)
	)
	(footprint ""
		(layer "F.Cu")
		(at 412.956502 -286.530034 90)
		(property "Reference" "R593"
			(at 0 0 90)
			(layer "F.SilkS")
			(hide yes)
			(effects
				(font
					(size 1.27 1.27)
				)
			)
		)
		(property "Value" "4K7R2J-2-GP"
			(at 0.064008 -3.993896 90)
			(unlocked yes)
			(layer "F.Fab")
			(hide yes)
			(effects
				(font
					(size 1.016 1.016)
					(thickness 0.1524)
				)
			)
		)
		(property "Device Type" "R402H16"
			(at 0.064008 -5.517896 90)
			(unlocked yes)
			(layer "F.Fab")
			(hide yes)
			(effects
				(font
					(size 1.016 1.016)
					(thickness 0.1524)
				)
			)
		)
		(duplicate_pad_numbers_are_jumpers no)
		(fp_line
			(start 0.508 -0.9398)
			(end -0.508 -0.9398)
			(stroke
				(width 0.1524)
				(type default)
			)
			(layer "F.SilkS")
		)
		(fp_line
			(start -0.508 -0.9398)
			(end -0.508 0.9398)
			(stroke
				(width 0.1524)
				(type default)
			)
			(layer "F.SilkS")
		)
		(fp_rect
			(start -0.508 0.9398)
			(end 0.508 -0.9398)
			(stroke
				(width 0)
				(type default)
			)
			(fill no)
			(layer "F.CrtYd")
		)
		(fp_rect
			(start -0.508 0.9398)
			(end 0.508 -0.9398)
			(stroke
				(width 0)
				(type default)
			)
			(fill no)
			(layer "F.Fab")
		)
		(pad "1" smd custom
			(at 0 -0.4445 90)
			(size 0.1397 0.1397)
			(layers "F.Cu" "F.Mask" "F.Paste")
			(net "DRIVE_B_33_FLT_LED")
			(options
				(clearance outline)
				(anchor circle)
			)
			(primitives
				(gr_poly
					(pts
						(arc
							(start -0.1778 -0.2794)
							(mid -0.249642 -0.249642)
							(end -0.2794 -0.1778)
						)
						(arc
							(start -0.2794 0.1778)
							(mid -0.249642 0.249642)
							(end -0.1778 0.2794)
						)
						(arc
							(start 0.1778 0.2794)
							(mid 0.249642 0.249642)
							(end 0.2794 0.1778)
						)
						(arc
							(start 0.2794 -0.1778)
							(mid 0.249642 -0.249642)
							(end 0.1778 -0.2794)
						)
					)
					(width 0)
					(fill yes)
				)
			)
		)
		(pad "2" smd custom
			(at 0 0.4445 90)
			(size 0.1397 0.1397)
			(layers "F.Cu" "F.Mask" "F.Paste")
			(net "GND")
			(options
				(clearance outline)
				(anchor circle)
			)
			(primitives
				(gr_poly
					(pts
						(arc
							(start -0.1778 -0.2794)
							(mid -0.249642 -0.249642)
							(end -0.2794 -0.1778)
						)
						(arc
							(start -0.2794 0.1778)
							(mid -0.249642 0.249642)
							(end -0.1778 0.2794)
						)
						(arc
							(start 0.1778 0.2794)
							(mid 0.249642 0.249642)
							(end 0.2794 0.1778)
						)
						(arc
							(start 0.2794 -0.1778)
							(mid 0.249642 -0.249642)
							(end 0.1778 -0.2794)
						)
					)
					(width 0)
					(fill yes)
				)
			)
		)
	)
	(footprint ""
		(layer "F.Cu")
		(at 133.228842 -181.42712 90)
		(property "Reference" "R470"
			(at 0 0 90)
			(layer "F.SilkS")
			(hide yes)
			(effects
				(font
					(size 1.27 1.27)
				)
			)
		)
		(property "Value" "4K7R2J-2-GP"
			(at 0.064008 -3.993896 90)
			(unlocked yes)
			(layer "F.Fab")
			(hide yes)
			(effects
				(font
					(size 1.016 1.016)
					(thickness 0.1524)
				)
			)
		)
		(property "Device Type" "R402H16"
			(at 0.064008 -5.517896 90)
			(unlocked yes)
			(layer "F.Fab")
			(hide yes)
			(effects
				(font
					(size 1.016 1.016)
					(thickness 0.1524)
				)
			)
		)
		(duplicate_pad_numbers_are_jumpers no)
		(fp_line
			(start 0.508 -0.9398)
			(end -0.508 -0.9398)
			(stroke
				(width 0.1524)
				(type default)
			)
			(layer "F.SilkS")
		)
		(fp_line
			(start -0.508 -0.9398)
			(end -0.508 0.9398)
			(stroke
				(width 0.1524)
				(type default)
			)
			(layer "F.SilkS")
		)
		(fp_rect
			(start -0.508 0.9398)
			(end 0.508 -0.9398)
			(stroke
				(width 0)
				(type default)
			)
			(fill no)
			(layer "F.CrtYd")
		)
		(fp_rect
			(start -0.508 0.9398)
			(end 0.508 -0.9398)
			(stroke
				(width 0)
				(type default)
			)
			(fill no)
			(layer "F.Fab")
		)
		(pad "1" smd custom
			(at 0 -0.4445 90)
			(size 0.1397 0.1397)
			(layers "F.Cu" "F.Mask" "F.Paste")
			(net "DRIVE_A_4_ACT")
			(options
				(clearance outline)
				(anchor circle)
			)
			(primitives
				(gr_poly
					(pts
						(arc
							(start -0.1778 -0.2794)
							(mid -0.249642 -0.249642)
							(end -0.2794 -0.1778)
						)
						(arc
							(start -0.2794 0.1778)
							(mid -0.249642 0.249642)
							(end -0.1778 0.2794)
						)
						(arc
							(start 0.1778 0.2794)
							(mid 0.249642 0.249642)
							(end 0.2794 0.1778)
						)
						(arc
							(start 0.2794 -0.1778)
							(mid 0.249642 -0.249642)
							(end 0.1778 -0.2794)
						)
					)
					(width 0)
					(fill yes)
				)
			)
		)
		(pad "2" smd custom
			(at 0 0.4445 90)
			(size 0.1397 0.1397)
			(layers "F.Cu" "F.Mask" "F.Paste")
			(net "GND")
			(options
				(clearance outline)
				(anchor circle)
			)
			(primitives
				(gr_poly
					(pts
						(arc
							(start -0.1778 -0.2794)
							(mid -0.249642 -0.249642)
							(end -0.2794 -0.1778)
						)
						(arc
							(start -0.2794 0.1778)
							(mid -0.249642 0.249642)
							(end -0.1778 0.2794)
						)
						(arc
							(start 0.1778 0.2794)
							(mid 0.249642 0.249642)
							(end 0.2794 0.1778)
						)
						(arc
							(start 0.2794 -0.1778)
							(mid 0.249642 -0.249642)
							(end 0.1778 -0.2794)
						)
					)
					(width 0)
					(fill yes)
				)
			)
		)
	)
	(footprint ""
		(layer "F.Cu")
		(at 332.105 -157.585918)
		(property "Reference" "R556"
			(at 0 0 0)
			(layer "F.SilkS")
			(hide yes)
			(effects
				(font
					(size 1.27 1.27)
				)
			)
		)
		(property "Value" "4K7R2J-2-GP"
			(at 0.064008 -3.993896 0)
			(unlocked yes)
			(layer "F.Fab")
			(hide yes)
			(effects
				(font
					(size 1.016 1.016)
					(thickness 0.1524)
				)
			)
		)
		(property "Device Type" "R402H16"
			(at 0.064008 -5.517896 0)
			(unlocked yes)
			(layer "F.Fab")
			(hide yes)
			(effects
				(font
					(size 1.016 1.016)
					(thickness 0.1524)
				)
			)
		)
		(duplicate_pad_numbers_are_jumpers no)
		(fp_line
			(start -0.508 -0.9398)
			(end -0.508 0.9398)
			(stroke
				(width 0.1524)
				(type default)
			)
			(layer "F.SilkS")
		)
		(fp_line
			(start 0.508 -0.9398)
			(end -0.508 -0.9398)
			(stroke
				(width 0.1524)
				(type default)
			)
			(layer "F.SilkS")
		)
		(fp_rect
			(start -0.508 0.9398)
			(end 0.508 -0.9398)
			(stroke
				(width 0)
				(type default)
			)
			(fill no)
			(layer "F.CrtYd")
		)
		(fp_rect
			(start -0.508 0.9398)
			(end 0.508 -0.9398)
			(stroke
				(width 0)
				(type default)
			)
			(fill no)
			(layer "F.Fab")
		)
		(pad "1" smd custom
			(at 0 -0.4445)
			(size 0.1397 0.1397)
			(layers "F.Cu" "F.Mask" "F.Paste")
			(net "SW_PWR_R_HDD18")
			(options
				(clearance outline)
				(anchor circle)
			)
			(primitives
				(gr_poly
					(pts
						(arc
							(start -0.1778 -0.2794)
							(mid -0.249642 -0.249642)
							(end -0.2794 -0.1778)
						)
						(arc
							(start -0.2794 0.1778)
							(mid -0.249642 0.249642)
							(end -0.1778 0.2794)
						)
						(arc
							(start 0.1778 0.2794)
							(mid 0.249642 0.249642)
							(end 0.2794 0.1778)
						)
						(arc
							(start 0.2794 -0.1778)
							(mid 0.249642 -0.249642)
							(end 0.1778 -0.2794)
						)
					)
					(width 0)
					(fill yes)
				)
			)
		)
		(pad "2" smd custom
			(at 0 0.4445)
			(size 0.1397 0.1397)
			(layers "F.Cu" "F.Mask" "F.Paste")
			(net "GND")
			(options
				(clearance outline)
				(anchor circle)
			)
			(primitives
				(gr_poly
					(pts
						(arc
							(start -0.1778 -0.2794)
							(mid -0.249642 -0.249642)
							(end -0.2794 -0.1778)
						)
						(arc
							(start -0.2794 0.1778)
							(mid -0.249642 0.249642)
							(end -0.1778 0.2794)
						)
						(arc
							(start 0.1778 0.2794)
							(mid 0.249642 0.249642)
							(end 0.2794 0.1778)
						)
						(arc
							(start 0.2794 -0.1778)
							(mid 0.249642 -0.249642)
							(end 0.1778 -0.2794)
						)
					)
					(width 0)
					(fill yes)
				)
			)
		)
	)
	(footprint ""
		(layer "F.Cu")
		(at 146.884898 -55.285894 180)
		(property "Reference" "Q168"
			(at 0 0 180)
			(layer "F.SilkS")
			(hide yes)
			(effects
				(font
					(size 1.27 1.27)
				)
			)
		)
		(property "Value" "AO4406AL-GP"
			(at -3.707384 -1.5367 180)
			(unlocked yes)
			(layer "F.Fab")
			(hide yes)
			(effects
				(font
					(size 1.016 1.016)
					(thickness 0.1524)
				)
			)
		)
		(property "Device Type" "SOIC8H69"
			(at -3.707384 -3.0607 180)
			(unlocked yes)
			(layer "F.Fab")
			(hide yes)
			(effects
				(font
					(size 1.016 1.016)
					(thickness 0.1524)
				)
			)
		)
		(duplicate_pad_numbers_are_jumpers no)
		(fp_line
			(start 2.1336 1.4224)
			(end 2.1336 -1.4224)
			(stroke
				(width 0.1524)
				(type default)
			)
			(layer "F.SilkS")
		)
		(fp_line
			(start 2.1336 -1.4224)
			(end -2.7432 -1.4224)
			(stroke
				(width 0.1524)
				(type default)
			)
			(layer "F.SilkS")
		)
		(fp_line
			(start -2.1844 -0.0508)
			(end -2.7178 0.508)
			(stroke
				(width 0.1524)
				(type default)
			)
			(layer "F.SilkS")
		)
		(fp_line
			(start -2.6289 3.4417)
			(end -2.6289 1.4732)
			(stroke
				(width 0.381)
				(type default)
			)
			(layer "F.SilkS")
		)
		(fp_line
			(start -2.7178 -0.508)
			(end -2.1844 -0.0508)
			(stroke
				(width 0.1524)
				(type default)
			)
			(layer "F.SilkS")
		)
		(fp_line
			(start -2.7432 1.4224)
			(end 2.1336 1.4224)
			(stroke
				(width 0.1524)
				(type default)
			)
			(layer "F.SilkS")
		)
		(fp_line
			(start -2.7432 1.4224)
			(end -2.6416 1.4224)
			(stroke
				(width 0.1524)
				(type default)
			)
			(layer "F.SilkS")
		)
		(fp_line
			(start -2.7432 -1.4224)
			(end -2.7432 1.4224)
			(stroke
				(width 0.1524)
				(type default)
			)
			(layer "F.SilkS")
		)
		(fp_poly
			(pts
				(xy -2.2098 -1.4224) (xy -2.2098 1.4224) (xy 2.2098 1.4224) (xy 2.2098 -1.4224)
			)
			(stroke
				(width 0)
				(type default)
			)
			(fill yes)
			(layer "F.SilkS")
		)
		(fp_rect
			(start -2.450084 2.999994)
			(end 2.450084 -2.999994)
			(stroke
				(width 0)
				(type default)
			)
			(fill no)
			(layer "F.CrtYd")
		)
		(fp_poly
			(pts
				(xy -2.8194 3.6322) (xy -2.8194 -3.6322) (xy 2.8194 -3.6322) (xy 2.8194 1.18364) (xy 2.450084 1.18364)
				(xy 2.450084 -2.999994) (xy -2.450084 -2.999994) (xy -2.450084 2.999994) (xy 2.450084 2.999994)
				(xy 2.450084 1.18618) (xy 2.8194 1.18618) (xy 2.8194 3.6322)
			)
			(stroke
				(width 0)
				(type default)
			)
			(fill no)
			(layer "F.CrtYd")
		)
		(fp_rect
			(start -2.8194 3.6322)
			(end 2.8194 -3.6322)
			(stroke
				(width 0)
				(type default)
			)
			(fill no)
			(layer "F.Fab")
		)
		(pad "1" smd rect
			(at -1.905 2.54 180)
			(size 0.635 1.651)
			(layers "F.Cu" "F.Mask" "F.Paste")
			(net "P5V_HDD28")
		)
		(pad "2" smd rect
			(at -0.635 2.54 180)
			(size 0.635 1.651)
			(layers "F.Cu" "F.Mask" "F.Paste")
			(net "P5V_HDD28")
		)
		(pad "3" smd rect
			(at 0.635 2.54 180)
			(size 0.635 1.651)
			(layers "F.Cu" "F.Mask" "F.Paste")
			(net "P5V_HDD28")
		)
		(pad "4" smd rect
			(at 1.905 2.54 180)
			(size 0.635 1.651)
			(layers "F.Cu" "F.Mask" "F.Paste")
			(net "SW_HDD_P28")
		)
		(pad "5" smd rect
			(at 1.905 -2.54 180)
			(size 0.635 1.651)
			(layers "F.Cu" "F.Mask" "F.Paste")
			(net "P5V_A_2")
		)
		(pad "6" smd rect
			(at 0.635 -2.54 180)
			(size 0.635 1.651)
			(layers "F.Cu" "F.Mask" "F.Paste")
			(net "P5V_A_2")
		)
		(pad "7" smd rect
			(at -0.635 -2.54 180)
			(size 0.635 1.651)
			(layers "F.Cu" "F.Mask" "F.Paste")
			(net "P5V_A_2")
		)
		(pad "8" smd rect
			(at -1.905 -2.54 180)
			(size 0.635 1.651)
			(layers "F.Cu" "F.Mask" "F.Paste")
			(net "P5V_A_2")
		)
	)
	(footprint ""
		(layer "F.Cu")
		(at 461.9879 -157.585918 180)
		(property "Reference" "R647"
			(at 0 0 180)
			(layer "F.SilkS")
			(hide yes)
			(effects
				(font
					(size 1.27 1.27)
				)
			)
		)
		(property "Value" "0R2J-2-GP"
			(at 0.064008 -3.993896 180)
			(unlocked yes)
			(layer "F.Fab")
			(hide yes)
			(effects
				(font
					(size 1.016 1.016)
					(thickness 0.1524)
				)
			)
		)
		(property "Device Type" "R402H16"
			(at 0.064008 -5.517896 180)
			(unlocked yes)
			(layer "F.Fab")
			(hide yes)
			(effects
				(font
					(size 1.016 1.016)
					(thickness 0.1524)
				)
			)
		)
		(duplicate_pad_numbers_are_jumpers no)
		(fp_line
			(start 0.508 -0.9398)
			(end -0.508 -0.9398)
			(stroke
				(width 0.1524)
				(type default)
			)
			(layer "F.SilkS")
		)
		(fp_line
			(start -0.508 -0.9398)
			(end -0.508 0.9398)
			(stroke
				(width 0.1524)
				(type default)
			)
			(layer "F.SilkS")
		)
		(fp_rect
			(start -0.508 0.9398)
			(end 0.508 -0.9398)
			(stroke
				(width 0)
				(type default)
			)
			(fill no)
			(layer "F.CrtYd")
		)
		(fp_rect
			(start -0.508 0.9398)
			(end 0.508 -0.9398)
			(stroke
				(width 0)
				(type default)
			)
			(fill no)
			(layer "F.Fab")
		)
		(pad "1" smd custom
			(at 0 -0.4445 180)
			(size 0.1397 0.1397)
			(layers "F.Cu" "F.Mask" "F.Paste")
			(net "DRIVE_A_22_PWR")
			(options
				(clearance outline)
				(anchor circle)
			)
			(primitives
				(gr_poly
					(pts
						(arc
							(start -0.1778 -0.2794)
							(mid -0.249642 -0.249642)
							(end -0.2794 -0.1778)
						)
						(arc
							(start -0.2794 0.1778)
							(mid -0.249642 0.249642)
							(end -0.1778 0.2794)
						)
						(arc
							(start 0.1778 0.2794)
							(mid 0.249642 0.249642)
							(end 0.2794 0.1778)
						)
						(arc
							(start 0.2794 -0.1778)
							(mid 0.249642 -0.249642)
							(end 0.1778 -0.2794)
						)
					)
					(width 0)
					(fill yes)
				)
			)
		)
		(pad "2" smd custom
			(at 0 0.4445 180)
			(size 0.1397 0.1397)
			(layers "F.Cu" "F.Mask" "F.Paste")
			(net "SW_PWR_R_HDD22")
			(options
				(clearance outline)
				(anchor circle)
			)
			(primitives
				(gr_poly
					(pts
						(arc
							(start -0.1778 -0.2794)
							(mid -0.249642 -0.249642)
							(end -0.2794 -0.1778)
						)
						(arc
							(start -0.2794 0.1778)
							(mid -0.249642 0.249642)
							(end -0.1778 0.2794)
						)
						(arc
							(start 0.1778 0.2794)
							(mid 0.249642 0.249642)
							(end 0.2794 0.1778)
						)
						(arc
							(start 0.2794 -0.1778)
							(mid 0.249642 -0.249642)
							(end 0.1778 -0.2794)
						)
					)
					(width 0)
					(fill yes)
				)
			)
		)
	)
)
